# BASEBOARD_FAB2 (Tioga Pass) — schematic netlist excerpt (pin names and nets, part order shuffled) for the footprints in the layout excerpt that follows; sources: Cadence DE-HDL packaged netlist, KiCad conversion of Wiwynn_Tioga_Pass_MB.brd

C7A24  CAP  1.0UF 16V 10% X6S  pkg 0402  page 219 : A = VR_PVDDQ_DEF_PH2_VCIN ; B = GND

T1D7  TEST-PAD-12P-1-GP-U  pkg DISCRET-GB1  page 257
  DP  = L10_85OHM_5INCH_DP
  DN  = L10_85OHM_5INCH_DN
  GND(0)  = GND
  GND(1)  = GND
  GND(2)  = GND
  GND(3)  = GND
  GND(4)  = GND
  GND(5)  = GND
  GND(6)  = GND
  GND(7)  = GND
  GND(8)  = GND
  GND(9)  = GND

(kicad_pcb
	(version 20260206)
	(generator "pcbnew")
	(generator_version "10.0")
	(general
		(thickness 1.6)
		(legacy_teardrops no)
	)
	(paper "A4")
	(title_block
		(title "Wiwynn_Tioga_Pass_MB.brd")
		(comment 1 "Tioga Pass / footprints 916-917 of 4770")
	)
	(layers
		(0 "F.Cu" signal "TOP")
		(4 "In1.Cu" signal "L2GND")
		(6 "In2.Cu" signal "L3")
		(8 "In3.Cu" signal "L4GND")
		(10 "In4.Cu" signal "L5")
		(12 "In5.Cu" signal "L6GND")
		(14 "In6.Cu" signal "L7VCC")
		(16 "In7.Cu" signal "L8VCC")
		(18 "In8.Cu" signal "L9GND")
		(20 "In9.Cu" signal "L10")
		(22 "In10.Cu" signal "L11GND")
		(24 "In11.Cu" signal "L12")
		(26 "In12.Cu" signal "L13GND")
		(2 "B.Cu" signal "BOTTOM")
		(9 "F.Adhes" user "F.Adhesive")
		(11 "B.Adhes" user "B.Adhesive")
		(13 "F.Paste" user "Package Geometry/Pastemask Top")
		(15 "B.Paste" user "Package Geometry/Pastemask Bottom")
		(5 "F.SilkS" user "Ref Des/Silkscreen Top")
		(7 "B.SilkS" user "Ref Des/Silkscreen Bottom")
		(1 "F.Mask" user "Board Geometry/Soldermask Top")
		(3 "B.Mask" user "Board Geometry/Soldermask Bottom")
		(17 "Dwgs.User" user "User.Drawings")
		(19 "Cmts.User" user "User.Comments")
		(21 "Eco1.User" user "User.Eco1")
		(23 "Eco2.User" user "User.Eco2")
		(25 "Edge.Cuts" user "Board Geometry/Outline")
		(27 "Margin" user)
		(31 "F.CrtYd" user "Package Geometry/Place Bound Top")
		(29 "B.CrtYd" user "Package Geometry/Place Bound Bottom")
		(35 "F.Fab" user "Ref Des/Assembly Top")
		(33 "B.Fab" user "Ref Des/Assembly Bottom")
	)
	(footprint ""
		(layer "F.Cu")
		(at 349.2246 -149.112224 90)
		(property "Reference" "C7A24"
			(at 0 0 90)
			(layer "F.SilkS")
			(hide yes)
			(effects
				(font
					(size 1.27 1.27)
				)
			)
		)
		(property "Value" ""
			(at 0 0 90)
			(layer "F.Fab")
			(effects
				(font
					(size 1.27 1.27)
				)
			)
		)
		(duplicate_pad_numbers_are_jumpers no)
		(fp_poly
			(pts
				(xy 0.3048 -0.1016) (xy 0.3048 0.9906) (xy -0.3048 0.9906) (xy -0.3048 -0.1016)
			)
			(stroke
				(width 0)
				(type default)
			)
			(fill no)
			(layer "F.CrtYd")
		)
		(fp_line
			(start 0.3048 -0.1016)
			(end -0.3048 -0.1016)
			(stroke
				(width 0.1)
				(type default)
			)
			(layer "F.Fab")
		)
		(fp_line
			(start -0.3048 -0.1016)
			(end -0.3048 0.9906)
			(stroke
				(width 0.1)
				(type default)
			)
			(layer "F.Fab")
		)
		(fp_line
			(start 0.3048 0.9906)
			(end 0.3048 -0.1016)
			(stroke
				(width 0.1)
				(type default)
			)
			(layer "F.Fab")
		)
		(fp_line
			(start -0.3048 0.9906)
			(end 0.3048 0.9906)
			(stroke
				(width 0.1)
				(type default)
			)
			(layer "F.Fab")
		)
		(pad "1" smd rect
			(at 0 0 90)
			(size 0.508 0.508)
			(layers "F.Cu" "F.Mask" "F.Paste")
			(net "VR_PVDDQ_DEF_PH2_VCIN")
		)
		(pad "2" smd rect
			(at 0 0.889 90)
			(size 0.508 0.508)
			(layers "F.Cu" "F.Mask" "F.Paste")
			(net "GND")
		)
		(zone
			(layer "F.Cu")
			(hatch none 0.5)
			(connect_pads
				(clearance 0)
			)
			(min_thickness 0.25)
			(keepout
				(tracks allowed)
				(vias not_allowed)
				(pads allowed)
				(copperpour not_allowed)
				(footprints allowed)
			)
			(placement
				(enabled no)
				(sheetname "")
			)
			(fill
				(thermal_gap 0.5)
				(thermal_bridge_width 0.5)
				(island_removal_mode 0)
			)
			(polygon
				(pts
					(xy 349.4786 -148.858224) (xy 349.4786 -149.366224) (xy 349.8596 -149.366224) (xy 349.8596 -148.858224)
				)
			)
		)
		(zone
			(layer "F.Cu")
			(hatch none 0.5)
			(connect_pads
				(clearance 0)
			)
			(min_thickness 0.25)
			(keepout
				(tracks not_allowed)
				(vias allowed)
				(pads allowed)
				(copperpour not_allowed)
				(footprints allowed)
			)
			(placement
				(enabled no)
				(sheetname "")
			)
			(fill
				(thermal_gap 0.5)
				(thermal_bridge_width 0.5)
				(island_removal_mode 0)
			)
			(polygon
				(pts
					(xy 349.8596 -148.858224) (xy 349.8596 -149.366224) (xy 349.4786 -149.366224) (xy 349.4786 -148.858224)
				)
			)
		)
	)
	(footprint ""
		(layer "F.Cu")
		(at 108.9025 -164.973 -90)
		(property "Reference" "T1D7"
			(at 0 0 270)
			(layer "F.SilkS")
			(hide yes)
			(effects
				(font
					(size 1.27 1.27)
				)
			)
		)
		(property "Value" "*"
			(at -3.4036 -4.46405 270)
			(unlocked yes)
			(layer "F.Fab")
			(hide yes)
			(effects
				(font
					(size 0.889 0.889)
					(thickness 0.1524)
				)
			)
		)
		(property "Device Type" "TEST-PAD-12P-1-GP-U_DISCRET-GBA"
			(at -3.4036 -5.98805 270)
			(unlocked yes)
			(layer "F.Fab")
			(hide yes)
			(effects
				(font
					(size 0.889 0.889)
					(thickness 0.1524)
				)
			)
		)
		(duplicate_pad_numbers_are_jumpers no)
		(fp_line
			(start -2.3876 3.4798)
			(end -2.3876 -4.826)
			(stroke
				(width 0.1524)
				(type default)
			)
			(layer "F.SilkS")
		)
		(fp_line
			(start 2.3622 3.4798)
			(end -2.3876 3.4798)
			(stroke
				(width 0.1524)
				(type default)
			)
			(layer "F.SilkS")
		)
		(fp_line
			(start -2.3876 -4.826)
			(end 2.3622 -4.826)
			(stroke
				(width 0.1524)
				(type default)
			)
			(layer "F.SilkS")
		)
		(fp_line
			(start 2.3622 -4.826)
			(end 2.3622 3.4798)
			(stroke
				(width 0.1524)
				(type default)
			)
			(layer "F.SilkS")
		)
		(fp_rect
			(start -2.6416 3.7338)
			(end 2.6162 -5.08)
			(stroke
				(width 0)
				(type default)
			)
			(fill no)
			(layer "F.CrtYd")
		)
		(fp_rect
			(start -2.6416 3.7338)
			(end 2.6162 -5.08)
			(stroke
				(width 0)
				(type default)
			)
			(fill no)
			(layer "F.Fab")
		)
		(pad "1" smd circle
			(at 0.496824 -1.301496 270)
			(size 0.6604 0.6604)
			(layers "F.Cu" "F.Mask" "F.Paste")
			(net "L10_85OHM_5INCH_DP")
		)
		(pad "2" smd circle
			(at -0.503936 -1.301496 270)
			(size 0.6604 0.6604)
			(layers "F.Cu" "F.Mask" "F.Paste")
			(net "L10_85OHM_5INCH_DN")
		)
		(pad "3" smd custom
			(at -0.00889 0.370078 270)
			(size 0.74295 0.74295)
			(layers "F.Cu" "F.Mask" "F.Paste")
			(net "GND")
			(options
				(clearance outline)
				(anchor circle)
			)
			(primitives
				(gr_poly
					(pts
						(xy -2.1209 1.4859) (xy 2.1209 1.4859) (xy 2.1209 -1.4859) (xy 1.08585 -1.4859) (xy 1.08585 -0.4699)
						(xy -1.08585 -0.4699) (xy -1.08585 -1.4859) (xy -2.1209 -1.4859)
					)
					(width 0)
					(fill yes)
				)
			)
		)
		(pad "4" thru_hole circle
			(at 1.266444 -3.851656 270)
			(size 1.4478 1.4478)
			(drill 1.0414)
			(layers "*.Cu" "*.Mask")
			(remove_unused_layers no)
			(net "GND")
			(clearance 0.1524)
			(thermal_gap 0.1524)
		)
		(pad "5" thru_hole circle
			(at -1.273556 -3.851656 270)
			(size 1.4478 1.4478)
			(drill 1.0414)
			(layers "*.Cu" "*.Mask")
			(remove_unused_layers no)
			(net "GND")
			(clearance 0.1524)
			(thermal_gap 0.1524)
		)
		(pad "6" thru_hole circle
			(at 1.266444 2.498344 270)
			(size 1.4478 1.4478)
			(drill 1.0414)
			(layers "*.Cu" "*.Mask")
			(remove_unused_layers no)
			(net "GND")
			(clearance 0.1524)
			(thermal_gap 0.1524)
		)
		(pad "7" thru_hole circle
			(at -1.273556 2.498344 270)
			(size 1.4478 1.4478)
			(drill 1.0414)
			(layers "*.Cu" "*.Mask")
			(remove_unused_layers no)
			(net "GND")
			(clearance 0.1524)
			(thermal_gap 0.1524)
		)
		(pad "8" thru_hole circle
			(at 1.27 -0.4572 270)
			(size 0.7112 0.7112)
			(drill 0.4064)
			(layers "*.Cu" "*.Mask")
			(remove_unused_layers no)
			(net "GND")
			(clearance 0.1016)
			(thermal_gap 0.1016)
		)
		(pad "9" thru_hole circle
			(at 1.27 0.762 270)
			(size 0.7112 0.7112)
			(drill 0.4064)
			(layers "*.Cu" "*.Mask")
			(remove_unused_layers no)
			(net "GND")
			(clearance 0.1016)
			(thermal_gap 0.1016)
		)
		(pad "10" thru_hole circle
			(at -0.0254 0.762 270)
			(size 0.7112 0.7112)
			(drill 0.4064)
			(layers "*.Cu" "*.Mask")
			(remove_unused_layers no)
			(net "GND")
			(clearance 0.1016)
			(thermal_gap 0.1016)
		)
		(pad "11" thru_hole circle
			(at -1.27 0.762 270)
			(size 0.7112 0.7112)
			(drill 0.4064)
			(layers "*.Cu" "*.Mask")
			(remove_unused_layers no)
			(net "GND")
			(clearance 0.1016)
			(thermal_gap 0.1016)
		)
		(pad "12" thru_hole circle
			(at -1.27 -0.4572 270)
			(size 0.7112 0.7112)
			(drill 0.4064)
			(layers "*.Cu" "*.Mask")
			(remove_unused_layers no)
			(net "GND")
			(clearance 0.1016)
			(thermal_gap 0.1016)
		)
	)
)
